# S9S_MB_2U (Grand Teton) — schematic netlist excerpt (pin names and nets, part order shuffled) for the footprints in the layout excerpt that follows; sources: Cadence DE-HDL packaged netlist, KiCad conversion of 03242023_DA0F0TMBIJ0_F0T_Motherboard_J_brd_V01_OCP.brd

R1442  Q_RES  33.2 1% CHIP  pkg 0402LF  page 222 : A = PWRGD_PCH_PWROK_R ; B = PWRGD_PCH_PWROK
R1238  Q_RES  240 1% EMPTY  pkg 0402LF  page 119 : A = GND ; B = PUD_XTAL_CPU0_MODE0

(kicad_pcb
	(version 20260206)
	(generator "pcbnew")
	(generator_version "10.0")
	(general
		(thickness 1.6)
		(legacy_teardrops no)
	)
	(paper "A4")
	(title_block
		(title "03242023_DA0F0TMBIJ0_F0T_Motherboard_J_brd_V01_OCP.brd")
		(comment 1 "Grand Teton / footprints 2105-2106 of 6105")
	)
	(layers
		(0 "F.Cu" signal "TOP")
		(4 "In1.Cu" signal "GND")
		(6 "In2.Cu" signal "IN1")
		(8 "In3.Cu" signal "GND1")
		(10 "In4.Cu" signal "IN2")
		(12 "In5.Cu" signal "GND2")
		(14 "In6.Cu" signal "IN3")
		(16 "In7.Cu" signal "GND3")
		(18 "In8.Cu" signal "VCC")
		(20 "In9.Cu" signal "VCC1")
		(22 "In10.Cu" signal "GND4")
		(24 "In11.Cu" signal "IN4")
		(26 "In12.Cu" signal "GND5")
		(28 "In13.Cu" signal "IN5")
		(30 "In14.Cu" signal "GND6")
		(32 "In15.Cu" signal "IN6")
		(34 "In16.Cu" signal "GND7")
		(2 "B.Cu" signal "BOTTOM")
		(9 "F.Adhes" user "F.Adhesive")
		(11 "B.Adhes" user "B.Adhesive")
		(13 "F.Paste" user "Package Geometry/Pastemask Top")
		(15 "B.Paste" user "Package Geometry/Pastemask Bottom")
		(5 "F.SilkS" user "Ref Des/Silkscreen Top")
		(7 "B.SilkS" user "Ref Des/Silkscreen Bottom")
		(1 "F.Mask" user "Board Geometry/Soldermask Top")
		(3 "B.Mask" user "Board Geometry/Soldermask Bottom")
		(17 "Dwgs.User" user "User.Drawings")
		(19 "Cmts.User" user "User.Comments")
		(21 "Eco1.User" user "User.Eco1")
		(23 "Eco2.User" user "User.Eco2")
		(25 "Edge.Cuts" user "Board Geometry/Outline")
		(27 "Margin" user)
		(31 "F.CrtYd" user "Package Geometry/Place Bound Top")
		(29 "B.CrtYd" user "Package Geometry/Place Bound Bottom")
		(35 "F.Fab" user "Ref Des/Assembly Top")
		(33 "B.Fab" user "Ref Des/Assembly Bottom")
	)
	(footprint ""
		(layer "F.Cu")
		(at 406.124664 -358.436926 180)
		(property "Reference" "R1238"
			(at 0 0 180)
			(layer "F.SilkS")
			(hide yes)
			(effects
				(font
					(size 1.27 1.27)
				)
			)
		)
		(property "Value" ""
			(at 0 0 180)
			(layer "F.Fab")
			(effects
				(font
					(size 1.27 1.27)
				)
			)
		)
		(duplicate_pad_numbers_are_jumpers no)
		(fp_line
			(start 0.7874 0.4064)
			(end -0.7874 0.4064)
			(stroke
				(width 0.1524)
				(type default)
			)
			(layer "F.SilkS")
		)
		(fp_line
			(start 0.7874 -0.4064)
			(end 0.7874 0.4064)
			(stroke
				(width 0.1524)
				(type default)
			)
			(layer "F.SilkS")
		)
		(fp_line
			(start -0.7874 0.4064)
			(end -0.7874 -0.4064)
			(stroke
				(width 0.1524)
				(type default)
			)
			(layer "F.SilkS")
		)
		(fp_line
			(start -0.7874 -0.4064)
			(end 0.7874 -0.4064)
			(stroke
				(width 0.1524)
				(type default)
			)
			(layer "F.SilkS")
		)
		(fp_line
			(start 0.67945 0.3048)
			(end 0.120396 0.3048)
			(stroke
				(width 0.1)
				(type default)
			)
			(layer "F.Fab")
		)
		(fp_line
			(start 0.67945 -0.3048)
			(end 0.67945 0.3048)
			(stroke
				(width 0.1)
				(type default)
			)
			(layer "F.Fab")
		)
		(fp_line
			(start 0.12065 -0.2794)
			(end 0.12065 -0.3048)
			(stroke
				(width 0.1)
				(type default)
			)
			(layer "F.Fab")
		)
		(fp_line
			(start 0.12065 -0.3048)
			(end 0.67945 -0.3048)
			(stroke
				(width 0.1)
				(type default)
			)
			(layer "F.Fab")
		)
		(fp_line
			(start 0.120396 0.3048)
			(end 0.120396 0.2794)
			(stroke
				(width 0.1)
				(type default)
			)
			(layer "F.Fab")
		)
		(fp_line
			(start 0.120396 0.2794)
			(end -0.12065 0.2794)
			(stroke
				(width 0.1)
				(type default)
			)
			(layer "F.Fab")
		)
		(fp_line
			(start -0.12065 0.3048)
			(end -0.67945 0.3048)
			(stroke
				(width 0.1)
				(type default)
			)
			(layer "F.Fab")
		)
		(fp_line
			(start -0.12065 0.2794)
			(end -0.12065 0.3048)
			(stroke
				(width 0.1)
				(type default)
			)
			(layer "F.Fab")
		)
		(fp_line
			(start -0.12065 -0.2794)
			(end 0.12065 -0.2794)
			(stroke
				(width 0.1)
				(type default)
			)
			(layer "F.Fab")
		)
		(fp_line
			(start -0.12065 -0.305054)
			(end -0.12065 -0.2794)
			(stroke
				(width 0.1)
				(type default)
			)
			(layer "F.Fab")
		)
		(fp_line
			(start -0.67945 0.3048)
			(end -0.67945 -0.305054)
			(stroke
				(width 0.1)
				(type default)
			)
			(layer "F.Fab")
		)
		(fp_line
			(start -0.67945 -0.305054)
			(end -0.12065 -0.305054)
			(stroke
				(width 0.1)
				(type default)
			)
			(layer "F.Fab")
		)
		(pad "1" smd circle
			(at -0.40005 0 180)
			(size 0 0)
			(layers "F.Cu" "F.Mask" "F.Paste")
			(net "GND")
		)
		(pad "2" smd circle
			(at 0.40005 0 180)
			(size 0 0)
			(layers "F.Cu" "F.Mask" "F.Paste")
			(net "PUD_XTAL_CPU0_MODE0")
		)
	)
	(footprint ""
		(layer "F.Cu")
		(at 315.946028 -25.09139)
		(property "Reference" "R1442"
			(at 0 0 0)
			(layer "F.SilkS")
			(hide yes)
			(effects
				(font
					(size 1.27 1.27)
				)
			)
		)
		(property "Value" ""
			(at 0 0 0)
			(layer "F.Fab")
			(effects
				(font
					(size 1.27 1.27)
				)
			)
		)
		(duplicate_pad_numbers_are_jumpers no)
		(fp_line
			(start -0.7874 -0.4064)
			(end 0.7874 -0.4064)
			(stroke
				(width 0.1524)
				(type default)
			)
			(layer "F.SilkS")
		)
		(fp_line
			(start -0.7874 0.4064)
			(end -0.7874 -0.4064)
			(stroke
				(width 0.1524)
				(type default)
			)
			(layer "F.SilkS")
		)
		(fp_line
			(start 0.7874 -0.4064)
			(end 0.7874 0.4064)
			(stroke
				(width 0.1524)
				(type default)
			)
			(layer "F.SilkS")
		)
		(fp_line
			(start 0.7874 0.4064)
			(end -0.7874 0.4064)
			(stroke
				(width 0.1524)
				(type default)
			)
			(layer "F.SilkS")
		)
		(fp_line
			(start -0.67945 -0.305054)
			(end -0.12065 -0.305054)
			(stroke
				(width 0.1)
				(type default)
			)
			(layer "F.Fab")
		)
		(fp_line
			(start -0.67945 0.3048)
			(end -0.67945 -0.305054)
			(stroke
				(width 0.1)
				(type default)
			)
			(layer "F.Fab")
		)
		(fp_line
			(start -0.12065 -0.305054)
			(end -0.12065 -0.2794)
			(stroke
				(width 0.1)
				(type default)
			)
			(layer "F.Fab")
		)
		(fp_line
			(start -0.12065 -0.2794)
			(end 0.12065 -0.2794)
			(stroke
				(width 0.1)
				(type default)
			)
			(layer "F.Fab")
		)
		(fp_line
			(start -0.12065 0.2794)
			(end -0.12065 0.3048)
			(stroke
				(width 0.1)
				(type default)
			)
			(layer "F.Fab")
		)
		(fp_line
			(start -0.12065 0.3048)
			(end -0.67945 0.3048)
			(stroke
				(width 0.1)
				(type default)
			)
			(layer "F.Fab")
		)
		(fp_line
			(start 0.120396 0.2794)
			(end -0.12065 0.2794)
			(stroke
				(width 0.1)
				(type default)
			)
			(layer "F.Fab")
		)
		(fp_line
			(start 0.120396 0.3048)
			(end 0.120396 0.2794)
			(stroke
				(width 0.1)
				(type default)
			)
			(layer "F.Fab")
		)
		(fp_line
			(start 0.12065 -0.3048)
			(end 0.67945 -0.3048)
			(stroke
				(width 0.1)
				(type default)
			)
			(layer "F.Fab")
		)
		(fp_line
			(start 0.12065 -0.2794)
			(end 0.12065 -0.3048)
			(stroke
				(width 0.1)
				(type default)
			)
			(layer "F.Fab")
		)
		(fp_line
			(start 0.67945 -0.3048)
			(end 0.67945 0.3048)
			(stroke
				(width 0.1)
				(type default)
			)
			(layer "F.Fab")
		)
		(fp_line
			(start 0.67945 0.3048)
			(end 0.120396 0.3048)
			(stroke
				(width 0.1)
				(type default)
			)
			(layer "F.Fab")
		)
		(pad "1" smd circle
			(at -0.40005 0)
			(size 0 0)
			(layers "F.Cu" "F.Mask" "F.Paste")
			(net "PWRGD_PCH_PWROK_R")
		)
		(pad "2" smd circle
			(at 0.40005 0)
			(size 0 0)
			(layers "F.Cu" "F.Mask" "F.Paste")
			(net "PWRGD_PCH_PWROK")
		)
	)
)
